(kicad_pcb
	(version 20260206)
	(generator "pcbnew")
	(generator_version "10.0")
	(general
		(thickness 1.6)
		(legacy_teardrops no)
	)
	(paper "A4")
	(title_block
		(title "Bryce Canyon_F.DPB_16315-1-OCP.brd")
		(comment 1 "Bryce Canyon / footprints 1620-1626 of 2223")
	)
	(layers
		(0 "F.Cu" signal "TOP")
		(4 "In1.Cu" signal "L2GND")
		(6 "In2.Cu" signal "L3")
		(8 "In3.Cu" signal "L4GND")
		(10 "In4.Cu" signal "L5")
		(12 "In5.Cu" signal "L6VCC")
		(14 "In6.Cu" signal "L7VCC")
		(16 "In7.Cu" signal "L8")
		(18 "In8.Cu" signal "L9GND")
		(20 "In9.Cu" signal "L10")
		(22 "In10.Cu" signal "L11GND")
		(2 "B.Cu" signal "BOTTOM")
		(9 "F.Adhes" user "F.Adhesive")
		(11 "B.Adhes" user "B.Adhesive")
		(13 "F.Paste" user "Package Geometry/Pastemask Top")
		(15 "B.Paste" user "Package Geometry/Pastemask Bottom")
		(5 "F.SilkS" user "Ref Des/Silkscreen Top")
		(7 "B.SilkS" user "Ref Des/Silkscreen Bottom")
		(1 "F.Mask" user "Board Geometry/Soldermask Top")
		(3 "B.Mask" user "Board Geometry/Soldermask Bottom")
		(17 "Dwgs.User" user "User.Drawings")
		(19 "Cmts.User" user "User.Comments")
		(21 "Eco1.User" user "User.Eco1")
		(23 "Eco2.User" user "User.Eco2")
		(25 "Edge.Cuts" user "Board Geometry/Outline")
		(27 "Margin" user)
		(31 "F.CrtYd" user "Package Geometry/Place Bound Top")
		(29 "B.CrtYd" user "Package Geometry/Place Bound Bottom")
		(35 "F.Fab" user "Ref Des/Assembly Top")
		(33 "B.Fab" user "Ref Des/Assembly Bottom")
	)
	(footprint ""
		(layer "F.Cu")
		(at 235.99267 -261.68604)
		(property "Reference" "R32"
			(at 0 0 0)
			(layer "F.SilkS")
			(hide yes)
			(effects
				(font
					(size 1.27 1.27)
				)
			)
		)
		(property "Value" "4K7R2F-GP"
			(at 0.064008 -3.993896 0)
			(unlocked yes)
			(layer "F.Fab")
			(hide yes)
			(effects
				(font
					(size 1.016 1.016)
					(thickness 0.1524)
				)
			)
		)
		(property "Device Type" "R402H16"
			(at 0.064008 -5.517896 0)
			(unlocked yes)
			(layer "F.Fab")
			(hide yes)
			(effects
				(font
					(size 1.016 1.016)
					(thickness 0.1524)
				)
			)
		)
		(duplicate_pad_numbers_are_jumpers no)
		(fp_line
			(start -0.508 -0.9398)
			(end -0.508 0.9398)
			(stroke
				(width 0.1524)
				(type default)
			)
			(layer "F.SilkS")
		)
		(fp_line
			(start 0.508 -0.9398)
			(end -0.508 -0.9398)
			(stroke
				(width 0.1524)
				(type default)
			)
			(layer "F.SilkS")
		)
		(fp_rect
			(start -0.508 0.9398)
			(end 0.508 -0.9398)
			(stroke
				(width 0)
				(type default)
			)
			(fill no)
			(layer "F.CrtYd")
		)
		(fp_rect
			(start -0.508 0.9398)
			(end 0.508 -0.9398)
			(stroke
				(width 0)
				(type default)
			)
			(fill no)
			(layer "F.Fab")
		)
		(pad "1" smd custom
			(at 0 -0.4445)
			(size 0.1397 0.1397)
			(layers "F.Cu" "F.Mask" "F.Paste")
			(net "P3V3_STBY_A")
			(options
				(clearance outline)
				(anchor circle)
			)
			(primitives
				(gr_poly
					(pts
						(arc
							(start -0.1778 -0.2794)
							(mid -0.249642 -0.249642)
							(end -0.2794 -0.1778)
						)
						(arc
							(start -0.2794 0.1778)
							(mid -0.249642 0.249642)
							(end -0.1778 0.2794)
						)
						(arc
							(start 0.1778 0.2794)
							(mid 0.249642 0.249642)
							(end 0.2794 0.1778)
						)
						(arc
							(start 0.2794 -0.1778)
							(mid 0.249642 -0.249642)
							(end 0.1778 -0.2794)
						)
					)
					(width 0)
					(fill yes)
				)
			)
		)
		(pad "2" smd custom
			(at 0 0.4445)
			(size 0.1397 0.1397)
			(layers "F.Cu" "F.Mask" "F.Paste")
			(net "IO_EXP4_A1")
			(options
				(clearance outline)
				(anchor circle)
			)
			(primitives
				(gr_poly
					(pts
						(arc
							(start -0.1778 -0.2794)
							(mid -0.249642 -0.249642)
							(end -0.2794 -0.1778)
						)
						(arc
							(start -0.2794 0.1778)
							(mid -0.249642 0.249642)
							(end -0.1778 0.2794)
						)
						(arc
							(start 0.1778 0.2794)
							(mid 0.249642 0.249642)
							(end 0.2794 0.1778)
						)
						(arc
							(start 0.2794 -0.1778)
							(mid 0.249642 -0.249642)
							(end 0.1778 -0.2794)
						)
					)
					(width 0)
					(fill yes)
				)
			)
		)
	)
	(footprint ""
		(layer "F.Cu")
		(at 237.115096 -234.9246 180)
		(property "Reference" "C21"
			(at 0 0 180)
			(layer "F.SilkS")
			(hide yes)
			(effects
				(font
					(size 1.27 1.27)
				)
			)
		)
		(property "Value" "SC1U16V3KX-5GP"
			(at 0 -2.8194 180)
			(unlocked yes)
			(layer "F.Fab")
			(hide yes)
			(effects
				(font
					(size 1.016 1.016)
					(thickness 0.1524)
				)
			)
		)
		(property "Device Type" "C603H36"
			(at 0 -4.3434 180)
			(unlocked yes)
			(layer "F.Fab")
			(hide yes)
			(effects
				(font
					(size 1.016 1.016)
					(thickness 0.1524)
				)
			)
		)
		(duplicate_pad_numbers_are_jumpers no)
		(fp_line
			(start 0.508 0)
			(end -0.508 0)
			(stroke
				(width 0.2032)
				(type default)
			)
			(layer "F.SilkS")
		)
		(fp_rect
			(start -0.5842 1.3335)
			(end 0.5842 -1.3335)
			(stroke
				(width 0)
				(type default)
			)
			(fill no)
			(layer "F.CrtYd")
		)
		(fp_rect
			(start -0.5842 1.3335)
			(end 0.5842 -1.3335)
			(stroke
				(width 0)
				(type default)
			)
			(fill no)
			(layer "F.Fab")
		)
		(pad "1" smd custom
			(at 0 -0.762 180)
			(size 0.2159 0.2159)
			(layers "F.Cu" "F.Mask" "F.Paste")
			(net "GPIO_VCC_U7")
			(options
				(clearance outline)
				(anchor circle)
			)
			(primitives
				(gr_poly
					(pts
						(arc
							(start -0.3302 -0.4318)
							(mid -0.402042 -0.402042)
							(end -0.4318 -0.3302)
						)
						(arc
							(start -0.4318 0.3302)
							(mid -0.402042 0.402042)
							(end -0.3302 0.4318)
						)
						(arc
							(start 0.3302 0.4318)
							(mid 0.402042 0.402042)
							(end 0.4318 0.3302)
						)
						(arc
							(start 0.4318 -0.3302)
							(mid 0.402042 -0.402042)
							(end 0.3302 -0.4318)
						)
					)
					(width 0)
					(fill yes)
				)
			)
		)
		(pad "2" smd custom
			(at 0 0.762 180)
			(size 0.2159 0.2159)
			(layers "F.Cu" "F.Mask" "F.Paste")
			(net "GND")
			(options
				(clearance outline)
				(anchor circle)
			)
			(primitives
				(gr_poly
					(pts
						(arc
							(start -0.3302 -0.4318)
							(mid -0.402042 -0.402042)
							(end -0.4318 -0.3302)
						)
						(arc
							(start -0.4318 0.3302)
							(mid -0.402042 0.402042)
							(end -0.3302 0.4318)
						)
						(arc
							(start 0.3302 0.4318)
							(mid 0.402042 0.402042)
							(end 0.4318 0.3302)
						)
						(arc
							(start 0.4318 -0.3302)
							(mid 0.402042 -0.402042)
							(end 0.3302 -0.4318)
						)
					)
					(width 0)
					(fill yes)
				)
			)
		)
	)
	(footprint ""
		(layer "F.Cu")
		(at 370.259102 -56.809894 -90)
		(property "Reference" "R857"
			(at 0 0 270)
			(layer "F.SilkS")
			(hide yes)
			(effects
				(font
					(size 1.27 1.27)
				)
			)
		)
		(property "Value" "300KR2F-GP"
			(at 0.064008 -3.993896 270)
			(unlocked yes)
			(layer "F.Fab")
			(hide yes)
			(effects
				(font
					(size 1.016 1.016)
					(thickness 0.1524)
				)
			)
		)
		(property "Device Type" "R402H16"
			(at 0.064008 -5.517896 270)
			(unlocked yes)
			(layer "F.Fab")
			(hide yes)
			(effects
				(font
					(size 1.016 1.016)
					(thickness 0.1524)
				)
			)
		)
		(duplicate_pad_numbers_are_jumpers no)
		(fp_line
			(start -0.508 -0.9398)
			(end -0.508 0.9398)
			(stroke
				(width 0.1524)
				(type default)
			)
			(layer "F.SilkS")
		)
		(fp_line
			(start 0.508 -0.9398)
			(end -0.508 -0.9398)
			(stroke
				(width 0.1524)
				(type default)
			)
			(layer "F.SilkS")
		)
		(fp_rect
			(start -0.508 0.9398)
			(end 0.508 -0.9398)
			(stroke
				(width 0)
				(type default)
			)
			(fill no)
			(layer "F.CrtYd")
		)
		(fp_rect
			(start -0.508 0.9398)
			(end 0.508 -0.9398)
			(stroke
				(width 0)
				(type default)
			)
			(fill no)
			(layer "F.Fab")
		)
		(pad "1" smd custom
			(at 0 -0.4445 270)
			(size 0.1397 0.1397)
			(layers "F.Cu" "F.Mask" "F.Paste")
			(net "SW_HDD_N31")
			(options
				(clearance outline)
				(anchor circle)
			)
			(primitives
				(gr_poly
					(pts
						(arc
							(start -0.1778 -0.2794)
							(mid -0.249642 -0.249642)
							(end -0.2794 -0.1778)
						)
						(arc
							(start -0.2794 0.1778)
							(mid -0.249642 0.249642)
							(end -0.1778 0.2794)
						)
						(arc
							(start 0.1778 0.2794)
							(mid 0.249642 0.249642)
							(end 0.2794 0.1778)
						)
						(arc
							(start 0.2794 -0.1778)
							(mid 0.249642 -0.249642)
							(end 0.1778 -0.2794)
						)
					)
					(width 0)
					(fill yes)
				)
			)
		)
		(pad "2" smd custom
			(at 0 0.4445 270)
			(size 0.1397 0.1397)
			(layers "F.Cu" "F.Mask" "F.Paste")
			(net "P12V_A")
			(options
				(clearance outline)
				(anchor circle)
			)
			(primitives
				(gr_poly
					(pts
						(arc
							(start -0.1778 -0.2794)
							(mid -0.249642 -0.249642)
							(end -0.2794 -0.1778)
						)
						(arc
							(start -0.2794 0.1778)
							(mid -0.249642 0.249642)
							(end -0.1778 0.2794)
						)
						(arc
							(start 0.1778 0.2794)
							(mid 0.249642 0.249642)
							(end 0.2794 0.1778)
						)
						(arc
							(start 0.2794 -0.1778)
							(mid 0.249642 -0.249642)
							(end 0.1778 -0.2794)
						)
					)
					(width 0)
					(fill yes)
				)
			)
		)
	)
	(footprint ""
		(layer "F.Cu")
		(at 395.20495 -160.252918 -90)
		(property "Reference" "Q121"
			(at 0 0 270)
			(layer "F.SilkS")
			(hide yes)
			(effects
				(font
					(size 1.27 1.27)
				)
			)
		)
		(property "Value" "2N7002KDW-GP"
			(at -2.3622 -8.2042 270)
			(unlocked yes)
			(layer "F.Fab")
			(hide yes)
			(effects
				(font
					(size 1.016 1.016)
					(thickness 0.1524)
				)
			)
		)
		(property "Device Type" "SOT-363H44"
			(at -2.3622 -10.1092 270)
			(unlocked yes)
			(layer "F.Fab")
			(hide yes)
			(effects
				(font
					(size 1.016 1.016)
					(thickness 0.1524)
				)
			)
		)
		(duplicate_pad_numbers_are_jumpers no)
		(fp_line
			(start -1.4478 1.7018)
			(end 1.4478 1.7018)
			(stroke
				(width 0.1524)
				(type default)
			)
			(layer "F.SilkS")
		)
		(fp_line
			(start 1.4478 1.7018)
			(end 1.4478 -1.7018)
			(stroke
				(width 0.1524)
				(type default)
			)
			(layer "F.SilkS")
		)
		(fp_line
			(start -1.27 1.524)
			(end -1.27 0.6604)
			(stroke
				(width 0.4826)
				(type default)
			)
			(layer "F.SilkS")
		)
		(fp_line
			(start -1.4478 -1.7018)
			(end -1.4478 1.7018)
			(stroke
				(width 0.1524)
				(type default)
			)
			(layer "F.SilkS")
		)
		(fp_line
			(start 1.4478 -1.7018)
			(end -1.4478 -1.7018)
			(stroke
				(width 0.1524)
				(type default)
			)
			(layer "F.SilkS")
		)
		(fp_poly
			(pts
				(xy -1.524 -1.778) (xy 1.524 -1.778) (xy 1.524 1.778) (xy -1.524 1.778)
			)
			(stroke
				(width 0)
				(type default)
			)
			(fill no)
			(layer "F.CrtYd")
		)
		(fp_poly
			(pts
				(xy -1.524 -1.778) (xy 1.524 -1.778) (xy 1.524 1.778) (xy -1.524 1.778)
			)
			(stroke
				(width 0)
				(type default)
			)
			(fill no)
			(layer "F.Fab")
		)
		(pad "1" smd rect
			(at -0.65024 0.9398 270)
			(size 0.4064 1.016)
			(layers "F.Cu" "F.Mask" "F.Paste")
			(net "GND")
		)
		(pad "2" smd rect
			(at 0 0.9398 270)
			(size 0.4064 1.016)
			(layers "F.Cu" "F.Mask" "F.Paste")
			(net "SW_PWR_R_HDD20")
		)
		(pad "3" smd rect
			(at 0.65024 0.9398 270)
			(size 0.4064 1.016)
			(layers "F.Cu" "F.Mask" "F.Paste")
			(net "SW_HDD_P20")
		)
		(pad "4" smd rect
			(at 0.65024 -0.9398 270)
			(size 0.4064 1.016)
			(layers "F.Cu" "F.Mask" "F.Paste")
			(net "GND")
		)
		(pad "5" smd rect
			(at 0 -0.9398 270)
			(size 0.4064 1.016)
			(layers "F.Cu" "F.Mask" "F.Paste")
			(net "SW_HDD_G20")
		)
		(pad "6" smd rect
			(at -0.65024 -0.9398 270)
			(size 0.4064 1.016)
			(layers "F.Cu" "F.Mask" "F.Paste")
			(net "SW_HDD_R20")
		)
	)
	(footprint ""
		(layer "F.Cu")
		(at 129.058162 -304.331878 180)
		(property "Reference" "R254"
			(at 0 0 180)
			(layer "F.SilkS")
			(hide yes)
			(effects
				(font
					(size 1.27 1.27)
				)
			)
		)
		(property "Value" "91R3F-1-GP"
			(at -0.0254 -2.5146 180)
			(unlocked yes)
			(layer "F.Fab")
			(hide yes)
			(effects
				(font
					(size 1.016 1.016)
					(thickness 0.1524)
				)
			)
		)
		(property "Device Type" "R603H22"
			(at -0.0254 -4.0386 180)
			(unlocked yes)
			(layer "F.Fab")
			(hide yes)
			(effects
				(font
					(size 1.016 1.016)
					(thickness 0.1524)
				)
			)
		)
		(duplicate_pad_numbers_are_jumpers no)
		(fp_line
			(start 0.2032 0)
			(end 0.4826 0)
			(stroke
				(width 0.2032)
				(type default)
			)
			(layer "F.SilkS")
		)
		(fp_line
			(start -0.4826 0)
			(end -0.2032 0)
			(stroke
				(width 0.2032)
				(type default)
			)
			(layer "F.SilkS")
		)
		(fp_rect
			(start -0.5842 1.3335)
			(end 0.5842 -1.3335)
			(stroke
				(width 0)
				(type default)
			)
			(fill no)
			(layer "F.CrtYd")
		)
		(fp_rect
			(start -0.5842 1.3335)
			(end 0.5842 -1.3335)
			(stroke
				(width 0)
				(type default)
			)
			(fill no)
			(layer "F.Fab")
		)
		(pad "1" smd custom
			(at 0 -0.762 180)
			(size 0.2159 0.2159)
			(layers "F.Cu" "F.Mask" "F.Paste")
			(net "P5V_B")
			(options
				(clearance outline)
				(anchor circle)
			)
			(primitives
				(gr_poly
					(pts
						(arc
							(start -0.3302 -0.4318)
							(mid -0.402042 -0.402042)
							(end -0.4318 -0.3302)
						)
						(arc
							(start -0.4318 0.3302)
							(mid -0.402042 0.402042)
							(end -0.3302 0.4318)
						)
						(arc
							(start 0.3302 0.4318)
							(mid 0.402042 0.402042)
							(end 0.4318 0.3302)
						)
						(arc
							(start 0.4318 -0.3302)
							(mid 0.402042 -0.402042)
							(end 0.3302 -0.4318)
						)
					)
					(width 0)
					(fill yes)
				)
			)
		)
		(pad "2" smd custom
			(at 0 0.762 180)
			(size 0.2159 0.2159)
			(layers "F.Cu" "F.Mask" "F.Paste")
			(net "DRV_ACT_28")
			(options
				(clearance outline)
				(anchor circle)
			)
			(primitives
				(gr_poly
					(pts
						(arc
							(start -0.3302 -0.4318)
							(mid -0.402042 -0.402042)
							(end -0.4318 -0.3302)
						)
						(arc
							(start -0.4318 0.3302)
							(mid -0.402042 0.402042)
							(end -0.3302 0.4318)
						)
						(arc
							(start 0.3302 0.4318)
							(mid 0.402042 0.402042)
							(end 0.4318 0.3302)
						)
						(arc
							(start 0.4318 -0.3302)
							(mid 0.402042 -0.402042)
							(end 0.3302 -0.4318)
						)
					)
					(width 0)
					(fill yes)
				)
			)
		)
	)
	(footprint ""
		(layer "F.Cu")
		(at 178.181 -62.778894 -90)
		(property "Reference" "C417"
			(at 0 0 270)
			(layer "F.SilkS")
			(hide yes)
			(effects
				(font
					(size 1.27 1.27)
				)
			)
		)
		(property "Value" "SC1U16V3KX-5GP"
			(at 0 -2.8194 270)
			(unlocked yes)
			(layer "F.Fab")
			(hide yes)
			(effects
				(font
					(size 1.016 1.016)
					(thickness 0.1524)
				)
			)
		)
		(property "Device Type" "C603H36"
			(at 0 -4.3434 270)
			(unlocked yes)
			(layer "F.Fab")
			(hide yes)
			(effects
				(font
					(size 1.016 1.016)
					(thickness 0.1524)
				)
			)
		)
		(duplicate_pad_numbers_are_jumpers no)
		(fp_line
			(start 0.508 0)
			(end -0.508 0)
			(stroke
				(width 0.2032)
				(type default)
			)
			(layer "F.SilkS")
		)
		(fp_rect
			(start -0.5842 1.3335)
			(end 0.5842 -1.3335)
			(stroke
				(width 0)
				(type default)
			)
			(fill no)
			(layer "F.CrtYd")
		)
		(fp_rect
			(start -0.5842 1.3335)
			(end 0.5842 -1.3335)
			(stroke
				(width 0)
				(type default)
			)
			(fill no)
			(layer "F.Fab")
		)
		(pad "1" smd custom
			(at 0 -0.762 270)
			(size 0.2159 0.2159)
			(layers "F.Cu" "F.Mask" "F.Paste")
			(net "P5V_HDD29")
			(options
				(clearance outline)
				(anchor circle)
			)
			(primitives
				(gr_poly
					(pts
						(arc
							(start -0.3302 -0.4318)
							(mid -0.402042 -0.402042)
							(end -0.4318 -0.3302)
						)
						(arc
							(start -0.4318 0.3302)
							(mid -0.402042 0.402042)
							(end -0.3302 0.4318)
						)
						(arc
							(start 0.3302 0.4318)
							(mid 0.402042 0.402042)
							(end 0.4318 0.3302)
						)
						(arc
							(start 0.4318 -0.3302)
							(mid 0.402042 -0.402042)
							(end 0.3302 -0.4318)
						)
					)
					(width 0)
					(fill yes)
				)
			)
		)
		(pad "2" smd custom
			(at 0 0.762 270)
			(size 0.2159 0.2159)
			(layers "F.Cu" "F.Mask" "F.Paste")
			(net "GND")
			(options
				(clearance outline)
				(anchor circle)
			)
			(primitives
				(gr_poly
					(pts
						(arc
							(start -0.3302 -0.4318)
							(mid -0.402042 -0.402042)
							(end -0.4318 -0.3302)
						)
						(arc
							(start -0.4318 0.3302)
							(mid -0.402042 0.402042)
							(end -0.3302 0.4318)
						)
						(arc
							(start 0.3302 0.4318)
							(mid 0.402042 0.402042)
							(end 0.4318 0.3302)
						)
						(arc
							(start 0.4318 -0.3302)
							(mid 0.402042 -0.402042)
							(end 0.3302 -0.4318)
						)
					)
					(width 0)
					(fill yes)
				)
			)
		)
	)
	(footprint ""
		(layer "F.Cu")
		(at 258.318 -279.908)
		(property "Reference" "C34"
			(at 0 0 0)
			(layer "F.SilkS")
			(hide yes)
			(effects
				(font
					(size 1.27 1.27)
				)
			)
		)
		(property "Value" "SC1U16V3KX-5GP"
			(at 0 -2.8194 0)
			(unlocked yes)
			(layer "F.Fab")
			(hide yes)
			(effects
				(font
					(size 1.016 1.016)
					(thickness 0.1524)
				)
			)
		)
		(property "Device Type" "C603H36"
			(at 0 -4.3434 0)
			(unlocked yes)
			(layer "F.Fab")
			(hide yes)
			(effects
				(font
					(size 1.016 1.016)
					(thickness 0.1524)
				)
			)
		)
		(duplicate_pad_numbers_are_jumpers no)
		(fp_line
			(start 0.508 0)
			(end -0.508 0)
			(stroke
				(width 0.2032)
				(type default)
			)
			(layer "F.SilkS")
		)
		(fp_rect
			(start -0.5842 1.3335)
			(end 0.5842 -1.3335)
			(stroke
				(width 0)
				(type default)
			)
			(fill no)
			(layer "F.CrtYd")
		)
		(fp_rect
			(start -0.5842 1.3335)
			(end 0.5842 -1.3335)
			(stroke
				(width 0)
				(type default)
			)
			(fill no)
			(layer "F.Fab")
		)
		(pad "1" smd custom
			(at 0 -0.762)
			(size 0.2159 0.2159)
			(layers "F.Cu" "F.Mask" "F.Paste")
			(net "P3V3_STBY_A")
			(options
				(clearance outline)
				(anchor circle)
			)
			(primitives
				(gr_poly
					(pts
						(arc
							(start -0.3302 -0.4318)
							(mid -0.402042 -0.402042)
							(end -0.4318 -0.3302)
						)
						(arc
							(start -0.4318 0.3302)
							(mid -0.402042 0.402042)
							(end -0.3302 0.4318)
						)
						(arc
							(start 0.3302 0.4318)
							(mid 0.402042 0.402042)
							(end 0.4318 0.3302)
						)
						(arc
							(start 0.4318 -0.3302)
							(mid 0.402042 -0.402042)
							(end 0.3302 -0.4318)
						)
					)
					(width 0)
					(fill yes)
				)
			)
		)
		(pad "2" smd custom
			(at 0 0.762)
			(size 0.2159 0.2159)
			(layers "F.Cu" "F.Mask" "F.Paste")
			(net "GND")
			(options
				(clearance outline)
				(anchor circle)
			)
			(primitives
				(gr_poly
					(pts
						(arc
							(start -0.3302 -0.4318)
							(mid -0.402042 -0.402042)
							(end -0.4318 -0.3302)
						)
						(arc
							(start -0.4318 0.3302)
							(mid -0.402042 0.402042)
							(end -0.3302 0.4318)
						)
						(arc
							(start 0.3302 0.4318)
							(mid 0.402042 0.402042)
							(end 0.4318 0.3302)
						)
						(arc
							(start 0.4318 -0.3302)
							(mid 0.402042 -0.402042)
							(end 0.3302 -0.4318)
						)
					)
					(width 0)
					(fill yes)
				)
			)
		)
	)
)
